FILE_TYPE = MACRO_DRAWING;
SET COLOR_WIRE YELLOW;
SET COLOR_PROP ORANGE;
SET COLOR_DOT WHITE;
SET COLOR_ARC YELLOW;
SET COLOR_BODY GREEN;
SET COLOR_NOTE PURPLE;
SET PROP_DISPLAY VALUE;
SET PAGE_NUMBER P193;
FORCEADD OFFPAGE..1
(-7275 350);
FORCEPROP 2 LAST $XR1 204 
J 0
(-7677 350);
DISPLAY 0.638298 (-7677 350);
PAINT MONO (-7677 350);
FORCEPROP 2 LAST $XR0 183 
J 0
(-7557 350);
DISPLAY 0.638298 (-7557 350);
PAINT MONO (-7557 350);
FORCEPROP 2 LAST CDS_LIB standard
J 0
(-7275 350);
PAINT MONO (-7275 350);
DISPLAY INVISIBLE (-7275 350);
FORCEPROP 1 LAST OFFPAGE TRUE
J 0
(-6950 225);
DISPLAY 0.872340 (-6950 225);
PAINT GREEN (-6950 225);
DISPLAY INVISIBLE (-6950 225);
FORCEPROP 1 LAST COMMENT_BODY TRUE
J 0
(-7150 250);
DISPLAY 0.872340 (-7150 250);
PAINT GREEN (-7150 250);
DISPLAY INVISIBLE (-7150 250);
FORCEPROP 2 LAST PATH I1
J 0
(-7225 425);
DISPLAY 1.021277 (-7225 425);
DISPLAY INVISIBLE (-7225 425);
FORCEADD Q_RES..1
(-5700 75);
FORCEPROP 1 LAST PART_NUMBER CS03322FB03
J 0
(-5800 150);
DISPLAY 0.510638 (-5800 150);
DISPLAY INVISIBLE (-5800 150);
FORCEPROP 1 LAST MATERIAL CHIP
J 0
(-5400 75);
DISPLAY 0.510638 (-5400 75);
FORCEPROP 1 LAST WATTAGE 1/16W
J 2
(-5500 200);
DISPLAY 0.510638 (-5500 200);
FORCEPROP 1 LAST PACK_TYPE 0402LF
J 0
(-5800 200);
DISPLAY 0.510638 (-5800 200);
FORCEPROP 1 LAST TOLERANCE 1%
J 0
(-5475 75);
DISPLAY 0.510638 (-5475 75);
FORCEPROP 1 LAST VALUE 33.2
J 2
(-5500 75);
DISPLAY 0.510638 (-5500 75);
FORCEPROP 1 LAST $LOCATION R1309
J 0
(-5950 75);
DISPLAY 0.638298 (-5950 75);
FORCEPROP 1 LASTPIN (-5800 75) $PN 1
J 0
(-5788 87);
DISPLAY 0.787234 (-5788 87);
FORCEPROP 1 LASTPIN (-5600 75) $PN 2
J 0
(-5638 87);
DISPLAY 0.787234 (-5638 87);
FORCEPROP 2 LAST CDS_LIB pure_quanta
J 0
(-5700 75);
PAINT MONO (-5700 75);
DISPLAY INVISIBLE (-5700 75);
FORCEPROP 1 LAST PATH I10
J 0
(-5750 225);
DISPLAY 0.978723 (-5750 225);
PAINT WHITE (-5750 225);
DISPLAY INVISIBLE (-5750 225);
FORCEPROP 1 LAST $LOCATION R1309
J 0
(-5750 275);
DISPLAY 1.021277 (-5750 275);
DISPLAY INVISIBLE (-5750 275);
FORCEPROP 2 LAST CDS_LOCATION R1309
J 0
(-5750 275);
DISPLAY 1.021277 (-5750 275);
DISPLAY INVISIBLE (-5750 275);
FORCEPROP 2 LAST $SEC 1
J 0
(-5750 275);
DISPLAY 0.680851 (-5750 275);
PAINT MONO (-5750 275);
DISPLAY INVISIBLE (-5750 275);
FORCEPROP 2 LAST CDS_SEC 1
J 0
(-5750 275);
DISPLAY 1.021277 (-5750 275);
DISPLAY INVISIBLE (-5750 275);
FORCEADD OFFPAGE..2
(-3925 625);
FORCEPROP 2 LAST $XR0 215 
J 0
(-3736 625);
DISPLAY 0.638298 (-3736 625);
PAINT MONO (-3736 625);
FORCEPROP 2 LAST CDS_LIB standard
J 0
(-3925 625);
PAINT MONO (-3925 625);
DISPLAY INVISIBLE (-3925 625);
FORCEPROP 1 LAST OFFPAGE TRUE
J 0
(-3600 500);
DISPLAY 1.170213 (-3600 500);
PAINT GREEN (-3600 500);
DISPLAY INVISIBLE (-3600 500);
FORCEPROP 1 LAST COMMENT_BODY TRUE
J 0
(-3970 530);
DISPLAY 1.170213 (-3970 530);
PAINT GREEN (-3970 530);
DISPLAY INVISIBLE (-3970 530);
FORCEPROP 2 LAST PATH I12
J 0
(-3725 675);
DISPLAY 1.021277 (-3725 675);
DISPLAY INVISIBLE (-3725 675);
FORCEADD Q_RES..1
(-5700 625);
FORCEPROP 1 LAST PART_NUMBER CS03322FB03
J 0
(-5800 700);
DISPLAY 0.510638 (-5800 700);
DISPLAY INVISIBLE (-5800 700);
FORCEPROP 1 LAST VALUE 33.2
J 2
(-5500 625);
DISPLAY 0.510638 (-5500 625);
FORCEPROP 1 LAST MATERIAL CHIP
J 0
(-5400 625);
DISPLAY 0.510638 (-5400 625);
FORCEPROP 1 LAST WATTAGE 1/16W
J 2
(-5500 750);
DISPLAY 0.510638 (-5500 750);
FORCEPROP 1 LAST PACK_TYPE 0402LF
J 0
(-5800 750);
DISPLAY 0.510638 (-5800 750);
FORCEPROP 1 LAST TOLERANCE 1%
J 0
(-5475 625);
DISPLAY 0.510638 (-5475 625);
FORCEPROP 1 LAST $LOCATION R1306
J 0
(-5950 625);
DISPLAY 0.638298 (-5950 625);
FORCEPROP 1 LASTPIN (-5800 625) $PN 1
J 0
(-5788 637);
DISPLAY 0.787234 (-5788 637);
FORCEPROP 1 LASTPIN (-5600 625) $PN 2
J 0
(-5638 637);
DISPLAY 0.787234 (-5638 637);
FORCEPROP 2 LAST CDS_LIB pure_quanta
J 0
(-5700 625);
PAINT MONO (-5700 625);
DISPLAY INVISIBLE (-5700 625);
FORCEPROP 1 LAST PATH I13
J 0
(-5750 775);
DISPLAY 0.978723 (-5750 775);
PAINT WHITE (-5750 775);
DISPLAY INVISIBLE (-5750 775);
FORCEPROP 1 LAST $LOCATION R1306
J 0
(-5750 825);
DISPLAY 1.021277 (-5750 825);
DISPLAY INVISIBLE (-5750 825);
FORCEPROP 2 LAST CDS_LOCATION R1306
J 0
(-5750 825);
DISPLAY 1.021277 (-5750 825);
DISPLAY INVISIBLE (-5750 825);
FORCEPROP 2 LAST $SEC 1
J 0
(-5750 825);
DISPLAY 0.680851 (-5750 825);
PAINT MONO (-5750 825);
DISPLAY INVISIBLE (-5750 825);
FORCEPROP 2 LAST CDS_SEC 1
J 0
(-5750 825);
DISPLAY 1.021277 (-5750 825);
DISPLAY INVISIBLE (-5750 825);
FORCEADD OFFPAGE..1
(-7275 625);
FORCEPROP 2 LAST $XR1 204 
J 0
(-7677 625);
DISPLAY 0.638298 (-7677 625);
PAINT MONO (-7677 625);
FORCEPROP 2 LAST $XR0 184 
J 0
(-7557 625);
DISPLAY 0.638298 (-7557 625);
PAINT MONO (-7557 625);
FORCEPROP 2 LAST CDS_LIB standard
J 0
(-7275 625);
PAINT MONO (-7275 625);
DISPLAY INVISIBLE (-7275 625);
FORCEPROP 1 LAST OFFPAGE TRUE
J 0
(-6950 500);
DISPLAY 0.872340 (-6950 500);
PAINT GREEN (-6950 500);
DISPLAY INVISIBLE (-6950 500);
FORCEPROP 1 LAST COMMENT_BODY TRUE
J 0
(-7150 525);
DISPLAY 0.872340 (-7150 525);
PAINT GREEN (-7150 525);
DISPLAY INVISIBLE (-7150 525);
FORCEPROP 2 LAST PATH I14
J 0
(-7225 700);
DISPLAY 1.021277 (-7225 700);
DISPLAY INVISIBLE (-7225 700);
FORCEADD OFFPAGE..1
(-7275 -225);
FORCEPROP 2 LAST $XR1 204 
J 0
(-7677 -225);
DISPLAY 0.638298 (-7677 -225);
PAINT MONO (-7677 -225);
FORCEPROP 2 LAST $XR0 185 
J 0
(-7557 -225);
DISPLAY 0.638298 (-7557 -225);
PAINT MONO (-7557 -225);
FORCEPROP 2 LAST CDS_LIB standard
J 0
(-7275 -225);
PAINT MONO (-7275 -225);
DISPLAY INVISIBLE (-7275 -225);
FORCEPROP 1 LAST OFFPAGE TRUE
J 0
(-6950 -350);
DISPLAY 0.872340 (-6950 -350);
PAINT GREEN (-6950 -350);
DISPLAY INVISIBLE (-6950 -350);
FORCEPROP 1 LAST COMMENT_BODY TRUE
J 0
(-7150 -325);
DISPLAY 0.872340 (-7150 -325);
PAINT GREEN (-7150 -325);
DISPLAY INVISIBLE (-7150 -325);
FORCEPROP 2 LAST PATH I18
J 0
(-7225 -150);
DISPLAY 1.021277 (-7225 -150);
DISPLAY INVISIBLE (-7225 -150);
FORCEADD OFFPAGE..2
(-3925 -225);
FORCEPROP 2 LAST $XR0 215 
J 0
(-3736 -225);
DISPLAY 0.638298 (-3736 -225);
PAINT MONO (-3736 -225);
FORCEPROP 2 LAST CDS_LIB standard
J 0
(-3925 -225);
PAINT MONO (-3925 -225);
DISPLAY INVISIBLE (-3925 -225);
FORCEPROP 1 LAST OFFPAGE TRUE
J 0
(-3600 -350);
DISPLAY 1.170213 (-3600 -350);
PAINT GREEN (-3600 -350);
DISPLAY INVISIBLE (-3600 -350);
FORCEPROP 1 LAST COMMENT_BODY TRUE
J 0
(-3970 -320);
DISPLAY 1.170213 (-3970 -320);
PAINT GREEN (-3970 -320);
DISPLAY INVISIBLE (-3970 -320);
FORCEPROP 2 LAST PATH I19
J 0
(-3725 -175);
DISPLAY 1.021277 (-3725 -175);
DISPLAY INVISIBLE (-3725 -175);
FORCEADD OFFPAGE..2
(-3925 350);
FORCEPROP 2 LAST $XR0 215 
J 0
(-3736 350);
DISPLAY 0.638298 (-3736 350);
PAINT MONO (-3736 350);
FORCEPROP 2 LAST CDS_LIB standard
J 0
(-3925 350);
PAINT MONO (-3925 350);
DISPLAY INVISIBLE (-3925 350);
FORCEPROP 1 LAST OFFPAGE TRUE
J 0
(-3600 225);
DISPLAY 1.170213 (-3600 225);
PAINT GREEN (-3600 225);
DISPLAY INVISIBLE (-3600 225);
FORCEPROP 1 LAST COMMENT_BODY TRUE
J 0
(-3970 255);
DISPLAY 1.170213 (-3970 255);
PAINT GREEN (-3970 255);
DISPLAY INVISIBLE (-3970 255);
FORCEPROP 2 LAST PATH I2
J 0
(-3725 400);
DISPLAY 1.021277 (-3725 400);
DISPLAY INVISIBLE (-3725 400);
FORCEADD Q_RES..1
(-5700 -225);
FORCEPROP 1 LAST PART_NUMBER CS03322FB03
J 0
(-5800 -150);
DISPLAY 0.510638 (-5800 -150);
DISPLAY INVISIBLE (-5800 -150);
FORCEPROP 1 LAST WATTAGE 1/16W
J 2
(-5500 -100);
DISPLAY 0.510638 (-5500 -100);
FORCEPROP 1 LAST PACK_TYPE 0402LF
J 0
(-5800 -100);
DISPLAY 0.510638 (-5800 -100);
FORCEPROP 1 LAST TOLERANCE 1%
J 0
(-5475 -225);
DISPLAY 0.510638 (-5475 -225);
FORCEPROP 1 LAST VALUE 33.2
J 2
(-5500 -225);
DISPLAY 0.510638 (-5500 -225);
FORCEPROP 1 LAST MATERIAL CHIP
J 0
(-5400 -225);
DISPLAY 0.510638 (-5400 -225);
FORCEPROP 1 LAST $LOCATION R1310
J 0
(-5950 -225);
DISPLAY 0.638298 (-5950 -225);
FORCEPROP 1 LASTPIN (-5800 -225) $PN 1
J 0
(-5788 -213);
DISPLAY 0.787234 (-5788 -213);
FORCEPROP 1 LASTPIN (-5600 -225) $PN 2
J 0
(-5638 -213);
DISPLAY 0.787234 (-5638 -213);
FORCEPROP 2 LAST CDS_LIB pure_quanta
J 0
(-5700 -225);
PAINT MONO (-5700 -225);
DISPLAY INVISIBLE (-5700 -225);
FORCEPROP 1 LAST PATH I20
J 0
(-5750 -75);
DISPLAY 0.978723 (-5750 -75);
PAINT WHITE (-5750 -75);
DISPLAY INVISIBLE (-5750 -75);
FORCEPROP 1 LAST $LOCATION R1310
J 0
(-5750 -25);
DISPLAY 1.021277 (-5750 -25);
DISPLAY INVISIBLE (-5750 -25);
FORCEPROP 2 LAST CDS_LOCATION R1310
J 0
(-5750 -25);
DISPLAY 1.021277 (-5750 -25);
DISPLAY INVISIBLE (-5750 -25);
FORCEPROP 2 LAST $SEC 1
J 0
(-5750 -25);
DISPLAY 0.680851 (-5750 -25);
PAINT MONO (-5750 -25);
DISPLAY INVISIBLE (-5750 -25);
FORCEPROP 2 LAST CDS_SEC 1
J 0
(-5750 -25);
DISPLAY 1.021277 (-5750 -25);
DISPLAY INVISIBLE (-5750 -25);
FORCEADD Q_RES..1
(-5700 -525);
FORCEPROP 1 LAST PART_NUMBER CS03322FB03
J 0
(-5800 -450);
DISPLAY 0.510638 (-5800 -450);
DISPLAY INVISIBLE (-5800 -450);
FORCEPROP 1 LAST MATERIAL CHIP
J 0
(-5400 -525);
DISPLAY 0.510638 (-5400 -525);
FORCEPROP 1 LAST TOLERANCE 1%
J 0
(-5475 -525);
DISPLAY 0.510638 (-5475 -525);
FORCEPROP 1 LAST VALUE 33.2
J 2
(-5500 -525);
DISPLAY 0.510638 (-5500 -525);
FORCEPROP 1 LAST PACK_TYPE 0402LF
J 0
(-5800 -400);
DISPLAY 0.510638 (-5800 -400);
FORCEPROP 1 LAST WATTAGE 1/16W
J 2
(-5500 -400);
DISPLAY 0.510638 (-5500 -400);
FORCEPROP 1 LAST $LOCATION R1313
J 0
(-5950 -525);
DISPLAY 0.638298 (-5950 -525);
FORCEPROP 1 LASTPIN (-5800 -525) $PN 1
J 0
(-5788 -513);
DISPLAY 0.787234 (-5788 -513);
FORCEPROP 1 LASTPIN (-5600 -525) $PN 2
J 0
(-5638 -513);
DISPLAY 0.787234 (-5638 -513);
FORCEPROP 2 LAST CDS_LIB pure_quanta
J 0
(-5700 -525);
PAINT MONO (-5700 -525);
DISPLAY INVISIBLE (-5700 -525);
FORCEPROP 1 LAST PATH I21
J 0
(-5750 -375);
DISPLAY 0.978723 (-5750 -375);
PAINT WHITE (-5750 -375);
DISPLAY INVISIBLE (-5750 -375);
FORCEPROP 1 LAST $LOCATION R1313
J 0
(-5750 -325);
DISPLAY 1.021277 (-5750 -325);
DISPLAY INVISIBLE (-5750 -325);
FORCEPROP 2 LAST CDS_LOCATION R1313
J 0
(-5750 -325);
DISPLAY 1.021277 (-5750 -325);
DISPLAY INVISIBLE (-5750 -325);
FORCEPROP 2 LAST $SEC 1
J 0
(-5750 -325);
DISPLAY 0.680851 (-5750 -325);
PAINT MONO (-5750 -325);
DISPLAY INVISIBLE (-5750 -325);
FORCEPROP 2 LAST CDS_SEC 1
J 0
(-5750 -325);
DISPLAY 1.021277 (-5750 -325);
DISPLAY INVISIBLE (-5750 -325);
FORCEADD OFFPAGE..2
(-3925 -525);
FORCEPROP 2 LAST $XR0 215 
J 0
(-3736 -525);
DISPLAY 0.638298 (-3736 -525);
PAINT MONO (-3736 -525);
FORCEPROP 2 LAST CDS_LIB standard
J 0
(-3925 -525);
PAINT MONO (-3925 -525);
DISPLAY INVISIBLE (-3925 -525);
FORCEPROP 1 LAST OFFPAGE TRUE
J 0
(-3600 -650);
DISPLAY 1.170213 (-3600 -650);
PAINT GREEN (-3600 -650);
DISPLAY INVISIBLE (-3600 -650);
FORCEPROP 1 LAST COMMENT_BODY TRUE
J 0
(-3970 -620);
DISPLAY 1.170213 (-3970 -620);
PAINT GREEN (-3970 -620);
DISPLAY INVISIBLE (-3970 -620);
FORCEPROP 2 LAST PATH I22
J 0
(-3725 -475);
DISPLAY 1.021277 (-3725 -475);
DISPLAY INVISIBLE (-3725 -475);
FORCEADD OFFPAGE..1
(-7275 -525);
FORCEPROP 2 LAST $XR1 204 
J 0
(-7677 -525);
DISPLAY 0.638298 (-7677 -525);
PAINT MONO (-7677 -525);
FORCEPROP 2 LAST $XR0 183 
J 0
(-7557 -525);
DISPLAY 0.638298 (-7557 -525);
PAINT MONO (-7557 -525);
FORCEPROP 2 LAST CDS_LIB standard
J 0
(-7275 -525);
PAINT MONO (-7275 -525);
DISPLAY INVISIBLE (-7275 -525);
FORCEPROP 1 LAST OFFPAGE TRUE
J 0
(-6950 -650);
DISPLAY 0.872340 (-6950 -650);
PAINT GREEN (-6950 -650);
DISPLAY INVISIBLE (-6950 -650);
FORCEPROP 1 LAST COMMENT_BODY TRUE
J 0
(-7150 -625);
DISPLAY 0.872340 (-7150 -625);
PAINT GREEN (-7150 -625);
DISPLAY INVISIBLE (-7150 -625);
FORCEPROP 2 LAST PATH I23
J 0
(-7225 -450);
DISPLAY 1.021277 (-7225 -450);
DISPLAY INVISIBLE (-7225 -450);
FORCEADD OFFPAGE..2
(-3925 -1575);
FORCEPROP 2 LAST $XR2 185 
J 0
(-3496 -1575);
DISPLAY 0.638298 (-3496 -1575);
PAINT MONO (-3496 -1575);
FORCEPROP 2 LAST $XR1 198 
J 0
(-3616 -1575);
DISPLAY 0.638298 (-3616 -1575);
PAINT MONO (-3616 -1575);
FORCEPROP 2 LAST $XR0 131 
J 0
(-3736 -1575);
DISPLAY 0.638298 (-3736 -1575);
PAINT MONO (-3736 -1575);
FORCEPROP 2 LAST CDS_LIB standard
J 0
(-3925 -1575);
PAINT MONO (-3925 -1575);
DISPLAY INVISIBLE (-3925 -1575);
FORCEPROP 1 LAST OFFPAGE TRUE
J 0
(-3600 -1700);
DISPLAY 1.170213 (-3600 -1700);
PAINT GREEN (-3600 -1700);
DISPLAY INVISIBLE (-3600 -1700);
FORCEPROP 1 LAST COMMENT_BODY TRUE
J 0
(-3970 -1670);
DISPLAY 1.170213 (-3970 -1670);
PAINT GREEN (-3970 -1670);
DISPLAY INVISIBLE (-3970 -1670);
FORCEPROP 2 LAST PATH I25
J 0
(-3725 -1525);
DISPLAY 1.021277 (-3725 -1525);
DISPLAY INVISIBLE (-3725 -1525);
FORCEADD OFFPAGE..1
(-7275 -1575);
FORCEPROP 2 LAST $XR0 215 
J 0
(-7557 -1575);
DISPLAY 0.638298 (-7557 -1575);
PAINT MONO (-7557 -1575);
FORCEPROP 2 LAST CDS_LIB standard
J 0
(-7275 -1575);
PAINT MONO (-7275 -1575);
DISPLAY INVISIBLE (-7275 -1575);
FORCEPROP 1 LAST OFFPAGE TRUE
J 0
(-6950 -1700);
DISPLAY 0.872340 (-6950 -1700);
PAINT GREEN (-6950 -1700);
DISPLAY INVISIBLE (-6950 -1700);
FORCEPROP 1 LAST COMMENT_BODY TRUE
J 0
(-7150 -1675);
DISPLAY 0.872340 (-7150 -1675);
PAINT GREEN (-7150 -1675);
DISPLAY INVISIBLE (-7150 -1675);
FORCEPROP 2 LAST PATH I26
J 0
(-7225 -1500);
DISPLAY 1.021277 (-7225 -1500);
DISPLAY INVISIBLE (-7225 -1500);
FORCEADD Q_RES..1
(-5725 -1575);
FORCEPROP 1 LAST PART_NUMBER CS04992FB07
J 0
(-5800 -1525);
DISPLAY 0.510638 (-5800 -1525);
DISPLAY INVISIBLE (-5800 -1525);
FORCEPROP 1 LAST PACK_TYPE 0402LF
J 0
(-5800 -1475);
DISPLAY 0.510638 (-5800 -1475);
FORCEPROP 1 LAST WATTAGE 1/16W
J 2
(-5500 -1475);
DISPLAY 0.510638 (-5500 -1475);
FORCEPROP 1 LAST TOLERANCE 1%
J 0
(-5500 -1575);
DISPLAY 0.510638 (-5500 -1575);
FORCEPROP 1 LAST MATERIAL CHIP
J 0
(-5300 -1575);
DISPLAY 0.510638 (-5300 -1575);
FORCEPROP 1 LAST VALUE 49.9
J 2
(-5325 -1575);
DISPLAY 0.510638 (-5325 -1575);
FORCEPROP 1 LAST $LOCATION R1455
J 0
(-5975 -1575);
DISPLAY 0.638298 (-5975 -1575);
FORCEPROP 1 LASTPIN (-5825 -1575) $PN 1
J 0
(-5813 -1563);
DISPLAY 0.787234 (-5813 -1563);
FORCEPROP 1 LASTPIN (-5625 -1575) $PN 2
J 0
(-5663 -1563);
DISPLAY 0.787234 (-5663 -1563);
FORCEPROP 2 LAST CDS_LIB pure_quanta
J 0
(-5725 -1575);
PAINT MONO (-5725 -1575);
DISPLAY INVISIBLE (-5725 -1575);
FORCEPROP 1 LAST PATH I27
J 0
(-5775 -1425);
DISPLAY 0.978723 (-5775 -1425);
PAINT WHITE (-5775 -1425);
DISPLAY INVISIBLE (-5775 -1425);
FORCEPROP 2 LAST CDS_LOCATION R1455
J 0
(-5775 -1375);
DISPLAY 1.021277 (-5775 -1375);
DISPLAY INVISIBLE (-5775 -1375);
FORCEPROP 2 LAST $SEC 1
J 0
(-5775 -1375);
DISPLAY 0.680851 (-5775 -1375);
PAINT MONO (-5775 -1375);
DISPLAY INVISIBLE (-5775 -1375);
FORCEPROP 2 LAST CDS_SEC 1
J 0
(-5775 -1375);
DISPLAY 1.021277 (-5775 -1375);
DISPLAY INVISIBLE (-5775 -1375);
FORCEADD Q_RES..1
(-5725 -1800);
FORCEPROP 1 LAST PART_NUMBER CS04992FB07
J 0
(-5800 -1750);
DISPLAY 0.510638 (-5800 -1750);
DISPLAY INVISIBLE (-5800 -1750);
FORCEPROP 1 LAST PACK_TYPE 0402LF
J 0
(-5800 -1700);
DISPLAY 0.510638 (-5800 -1700);
FORCEPROP 1 LAST WATTAGE 1/16W
J 2
(-5500 -1700);
DISPLAY 0.510638 (-5500 -1700);
FORCEPROP 1 LAST TOLERANCE 1%
J 0
(-5500 -1800);
DISPLAY 0.510638 (-5500 -1800);
FORCEPROP 1 LAST MATERIAL CHIP
J 0
(-5300 -1800);
DISPLAY 0.510638 (-5300 -1800);
FORCEPROP 1 LAST VALUE 49.9
J 2
(-5325 -1800);
DISPLAY 0.510638 (-5325 -1800);
FORCEPROP 1 LAST $LOCATION R1456
J 0
(-5975 -1800);
DISPLAY 0.638298 (-5975 -1800);
FORCEPROP 1 LASTPIN (-5825 -1800) $PN 1
J 0
(-5813 -1788);
DISPLAY 0.787234 (-5813 -1788);
FORCEPROP 1 LASTPIN (-5625 -1800) $PN 2
J 0
(-5663 -1788);
DISPLAY 0.787234 (-5663 -1788);
FORCEPROP 2 LAST CDS_LIB pure_quanta
J 0
(-5725 -1800);
PAINT MONO (-5725 -1800);
DISPLAY INVISIBLE (-5725 -1800);
FORCEPROP 1 LAST PATH I28
J 0
(-5775 -1650);
DISPLAY 0.978723 (-5775 -1650);
PAINT WHITE (-5775 -1650);
DISPLAY INVISIBLE (-5775 -1650);
FORCEPROP 2 LAST CDS_LOCATION R1456
J 0
(-5775 -1600);
DISPLAY 1.021277 (-5775 -1600);
DISPLAY INVISIBLE (-5775 -1600);
FORCEPROP 2 LAST $SEC 1
J 0
(-5775 -1600);
DISPLAY 0.680851 (-5775 -1600);
PAINT MONO (-5775 -1600);
DISPLAY INVISIBLE (-5775 -1600);
FORCEPROP 2 LAST CDS_SEC 1
J 0
(-5775 -1600);
DISPLAY 1.021277 (-5775 -1600);
DISPLAY INVISIBLE (-5775 -1600);
FORCEADD OFFPAGE..2
(-3925 -1800);
FORCEPROP 2 LAST $XR0 183 
J 0
(-3736 -1800);
DISPLAY 0.638298 (-3736 -1800);
PAINT MONO (-3736 -1800);
FORCEPROP 2 LAST CDS_LIB standard
J 0
(-3925 -1800);
PAINT MONO (-3925 -1800);
DISPLAY INVISIBLE (-3925 -1800);
FORCEPROP 1 LAST OFFPAGE TRUE
J 0
(-3600 -1925);
DISPLAY 1.170213 (-3600 -1925);
PAINT GREEN (-3600 -1925);
DISPLAY INVISIBLE (-3600 -1925);
FORCEPROP 1 LAST COMMENT_BODY TRUE
J 0
(-3970 -1895);
DISPLAY 1.170213 (-3970 -1895);
PAINT GREEN (-3970 -1895);
DISPLAY INVISIBLE (-3970 -1895);
FORCEPROP 2 LAST PATH I29
J 0
(-3725 -1750);
DISPLAY 1.021277 (-3725 -1750);
DISPLAY INVISIBLE (-3725 -1750);
FORCEADD Q_RES..1
(-5700 350);
FORCEPROP 1 LAST PART_NUMBER CS03322FB03
J 0
(-5800 425);
DISPLAY 0.510638 (-5800 425);
DISPLAY INVISIBLE (-5800 425);
FORCEPROP 1 LAST VALUE 33.2
J 2
(-5500 350);
DISPLAY 0.510638 (-5500 350);
FORCEPROP 1 LAST MATERIAL CHIP
J 0
(-5400 350);
DISPLAY 0.510638 (-5400 350);
FORCEPROP 1 LAST TOLERANCE 1%
J 0
(-5475 350);
DISPLAY 0.510638 (-5475 350);
FORCEPROP 1 LAST WATTAGE 1/16W
J 2
(-5500 475);
DISPLAY 0.510638 (-5500 475);
FORCEPROP 1 LAST PACK_TYPE 0402LF
J 0
(-5800 475);
DISPLAY 0.510638 (-5800 475);
FORCEPROP 1 LAST $LOCATION R1307
J 0
(-5950 350);
DISPLAY 0.638298 (-5950 350);
FORCEPROP 1 LASTPIN (-5800 350) $PN 1
J 0
(-5788 362);
DISPLAY 0.787234 (-5788 362);
FORCEPROP 1 LASTPIN (-5600 350) $PN 2
J 0
(-5638 362);
DISPLAY 0.787234 (-5638 362);
FORCEPROP 2 LAST CDS_LIB pure_quanta
J 0
(-5700 350);
PAINT MONO (-5700 350);
DISPLAY INVISIBLE (-5700 350);
FORCEPROP 1 LAST PATH I3
J 0
(-5750 500);
DISPLAY 0.978723 (-5750 500);
PAINT WHITE (-5750 500);
DISPLAY INVISIBLE (-5750 500);
FORCEPROP 1 LAST $LOCATION R1307
J 0
(-5750 550);
DISPLAY 1.021277 (-5750 550);
DISPLAY INVISIBLE (-5750 550);
FORCEPROP 2 LAST CDS_LOCATION R1307
J 0
(-5750 550);
DISPLAY 1.021277 (-5750 550);
DISPLAY INVISIBLE (-5750 550);
FORCEPROP 2 LAST $SEC 1
J 0
(-5750 550);
DISPLAY 0.680851 (-5750 550);
PAINT MONO (-5750 550);
DISPLAY INVISIBLE (-5750 550);
FORCEPROP 2 LAST CDS_SEC 1
J 0
(-5750 550);
DISPLAY 1.021277 (-5750 550);
DISPLAY INVISIBLE (-5750 550);
FORCEADD OFFPAGE..1
(-7275 -1800);
FORCEPROP 2 LAST $XR0 214 
J 0
(-7557 -1800);
DISPLAY 0.638298 (-7557 -1800);
PAINT MONO (-7557 -1800);
FORCEPROP 2 LAST CDS_LIB standard
J 0
(-7275 -1800);
PAINT MONO (-7275 -1800);
DISPLAY INVISIBLE (-7275 -1800);
FORCEPROP 1 LAST OFFPAGE TRUE
J 0
(-6950 -1925);
DISPLAY 0.872340 (-6950 -1925);
PAINT GREEN (-6950 -1925);
DISPLAY INVISIBLE (-6950 -1925);
FORCEPROP 1 LAST COMMENT_BODY TRUE
J 0
(-7150 -1900);
DISPLAY 0.872340 (-7150 -1900);
PAINT GREEN (-7150 -1900);
DISPLAY INVISIBLE (-7150 -1900);
FORCEPROP 2 LAST PATH I30
J 0
(-7225 -1725);
DISPLAY 1.021277 (-7225 -1725);
DISPLAY INVISIBLE (-7225 -1725);
FORCEADD Q_RES..1
(-5725 -2275);
FORCEPROP 1 LAST PART_NUMBER CS04992FB07
J 0
(-5800 -2200);
DISPLAY 0.510638 (-5800 -2200);
DISPLAY INVISIBLE (-5800 -2200);
FORCEPROP 1 LAST TOLERANCE 1%
J 0
(-5500 -2275);
DISPLAY 0.510638 (-5500 -2275);
FORCEPROP 1 LAST VALUE 49.9
J 2
(-5300 -2275);
DISPLAY 0.510638 (-5300 -2275);
FORCEPROP 1 LAST PACK_TYPE 0402LF
J 0
(-5800 -2150);
DISPLAY 0.510638 (-5800 -2150);
FORCEPROP 1 LAST WATTAGE 1/16W
J 2
(-5500 -2150);
DISPLAY 0.510638 (-5500 -2150);
FORCEPROP 1 LAST MATERIAL CHIP
J 0
(-5300 -2275);
DISPLAY 0.510638 (-5300 -2275);
FORCEPROP 1 LAST $LOCATION R698
J 0
(-5975 -2275);
DISPLAY 0.638298 (-5975 -2275);
FORCEPROP 1 LASTPIN (-5825 -2275) $PN 1
J 0
(-5813 -2263);
DISPLAY 0.787234 (-5813 -2263);
FORCEPROP 1 LASTPIN (-5625 -2275) $PN 2
J 0
(-5663 -2263);
DISPLAY 0.787234 (-5663 -2263);
FORCEPROP 2 LAST CDS_LIB pure_quanta
J 0
(-5725 -2275);
PAINT MONO (-5725 -2275);
DISPLAY INVISIBLE (-5725 -2275);
FORCEPROP 1 LAST PATH I32
J 0
(-5775 -2125);
DISPLAY 0.978723 (-5775 -2125);
PAINT WHITE (-5775 -2125);
DISPLAY INVISIBLE (-5775 -2125);
FORCEPROP 2 LAST CDS_LOCATION R698
J 0
(-5775 -2075);
DISPLAY 1.021277 (-5775 -2075);
DISPLAY INVISIBLE (-5775 -2075);
FORCEPROP 2 LAST $SEC 1
J 0
(-5775 -2075);
DISPLAY 0.680851 (-5775 -2075);
PAINT MONO (-5775 -2075);
DISPLAY INVISIBLE (-5775 -2075);
FORCEPROP 2 LAST CDS_SEC 1
J 0
(-5775 -2075);
DISPLAY 1.021277 (-5775 -2075);
DISPLAY INVISIBLE (-5775 -2075);
FORCEADD OFFPAGE..5
(-7275 -2275);
FORCEPROP 2 LAST $XR0 183 
J 0
(-7530 -2275);
DISPLAY 0.638298 (-7530 -2275);
PAINT MONO (-7530 -2275);
FORCEPROP 2 LAST CDS_LIB standard
J 0
(-7275 -2275);
PAINT MONO (-7275 -2275);
DISPLAY INVISIBLE (-7275 -2275);
FORCEPROP 1 LAST OFFPAGE TRUE
J 0
(-6950 -2400);
DISPLAY 0.872340 (-6950 -2400);
DISPLAY INVISIBLE (-6950 -2400);
FORCEPROP 1 LAST COMMENT_BODY TRUE
J 0
(-7175 -2350);
DISPLAY 1.170213 (-7175 -2350);
PAINT GREEN (-7175 -2350);
DISPLAY INVISIBLE (-7175 -2350);
FORCEPROP 2 LAST PATH I36
J 0
(-7550 -2225);
DISPLAY 1.021277 (-7550 -2225);
DISPLAY INVISIBLE (-7550 -2225);
FORCEADD OFFPAGE..1
R 2
(-3925 -2275);
FORCEPROP 2 LAST $XR1 220 
J 0
(-3619 -2275);
DISPLAY 0.638298 (-3619 -2275);
PAINT MONO (-3619 -2275);
FORCEPROP 2 LAST $XR0 215 
J 0
(-3739 -2275);
DISPLAY 0.638298 (-3739 -2275);
PAINT MONO (-3739 -2275);
FORCEPROP 2 LAST CDS_LIB standard
J 0
(-3925 -2275);
PAINT MONO (-3925 -2275);
DISPLAY INVISIBLE (-3925 -2275);
FORCEPROP 1 LAST OFFPAGE TRUE
J 2
(-4250 -2400);
DISPLAY 1.170213 (-4250 -2400);
PAINT GREEN (-4250 -2400);
DISPLAY INVISIBLE (-4250 -2400);
FORCEPROP 1 LAST COMMENT_BODY TRUE
J 2
(-4050 -2375);
DISPLAY 1.170213 (-4050 -2375);
PAINT GREEN (-4050 -2375);
DISPLAY INVISIBLE (-4050 -2375);
FORCEPROP 2 LAST PATH I37
J 0
(-3725 -2225);
DISPLAY 1.021277 (-3725 -2225);
DISPLAY INVISIBLE (-3725 -2225);
FORCEADD OFFPAGE..1
(-7275 75);
FORCEPROP 2 LAST $XR1 204 
J 0
(-7677 75);
DISPLAY 0.638298 (-7677 75);
PAINT MONO (-7677 75);
FORCEPROP 2 LAST $XR0 185 
J 0
(-7557 75);
DISPLAY 0.638298 (-7557 75);
PAINT MONO (-7557 75);
FORCEPROP 2 LAST CDS_LIB standard
J 0
(-7275 75);
DISPLAY INVISIBLE (-7275 75);
FORCEPROP 1 LAST OFFPAGE TRUE
J 0
(-6950 -50);
DISPLAY 0.872340 (-6950 -50);
DISPLAY INVISIBLE (-6950 -50);
FORCEPROP 1 LAST COMMENT_BODY TRUE
J 0
(-7150 -25);
DISPLAY 0.872340 (-7150 -25);
PAINT GREEN (-7150 -25);
DISPLAY INVISIBLE (-7150 -25);
FORCEPROP 2 LAST PATH I38
J 0
(-7550 125);
DISPLAY 1.021277 (-7550 125);
DISPLAY INVISIBLE (-7550 125);
FORCEADD OFFPAGE..5
R 2
(-3925 75);
FORCEPROP 2 LAST $XR0 240 
J 0
(-3736 75);
DISPLAY 0.638298 (-3736 75);
PAINT MONO (-3736 75);
FORCEPROP 2 LAST CDS_LIB standard
J 0
(-3925 75);
DISPLAY INVISIBLE (-3925 75);
FORCEPROP 1 LAST OFFPAGE TRUE
J 2
(-4250 -50);
DISPLAY 0.872340 (-4250 -50);
DISPLAY INVISIBLE (-4250 -50);
FORCEPROP 1 LAST COMMENT_BODY TRUE
J 2
(-4025 0);
DISPLAY 0.872340 (-4025 0);
PAINT GREEN (-4025 0);
DISPLAY INVISIBLE (-4025 0);
FORCEPROP 2 LAST PATH I39
J 0
(-3575 125);
DISPLAY 1.021277 (-3575 125);
DISPLAY INVISIBLE (-3575 125);
FORCEADD OFFPAGE..2
(-3925 -825);
FORCEPROP 2 LAST $XR0 215 
J 0
(-3736 -825);
DISPLAY 0.638298 (-3736 -825);
PAINT MONO (-3736 -825);
FORCEPROP 2 LAST CDS_LIB standard
J 0
(-3925 -825);
PAINT MONO (-3925 -825);
DISPLAY INVISIBLE (-3925 -825);
FORCEPROP 1 LAST OFFPAGE TRUE
J 0
(-3600 -950);
DISPLAY 1.170213 (-3600 -950);
PAINT GREEN (-3600 -950);
DISPLAY INVISIBLE (-3600 -950);
FORCEPROP 1 LAST COMMENT_BODY TRUE
J 0
(-3970 -920);
DISPLAY 1.170213 (-3970 -920);
PAINT GREEN (-3970 -920);
DISPLAY INVISIBLE (-3970 -920);
FORCEPROP 2 LAST PATH I4
J 0
(-3725 -775);
DISPLAY 1.021277 (-3725 -775);
DISPLAY INVISIBLE (-3725 -775);
FORCEADD Q_RES..1
(-5750 -1025);
FORCEPROP 1 LAST PART_NUMBER CS03322FB03
J 0
(-5850 -950);
DISPLAY 0.510638 (-5850 -950);
DISPLAY INVISIBLE (-5850 -950);
FORCEPROP 1 LAST VALUE 33.2
J 2
(-5550 -1025);
DISPLAY 0.510638 (-5550 -1025);
FORCEPROP 1 LAST PACK_TYPE 0402LF
J 0
(-5850 -900);
DISPLAY 0.510638 (-5850 -900);
FORCEPROP 1 LAST WATTAGE 1/16W
J 2
(-5550 -900);
DISPLAY 0.510638 (-5550 -900);
FORCEPROP 1 LAST TOLERANCE 1%
J 0
(-5525 -1025);
DISPLAY 0.510638 (-5525 -1025);
FORCEPROP 1 LAST MATERIAL CHIP
J 0
(-5450 -1025);
DISPLAY 0.510638 (-5450 -1025);
FORCEPROP 1 LAST $LOCATION R3065
J 0
(-5800 -975);
DISPLAY 0.978723 (-5800 -975);
FORCEPROP 1 LASTPIN (-5850 -1025) $PN 1
J 0
(-5838 -1013);
DISPLAY 0.787234 (-5838 -1013);
PAINT MONO (-5838 -1013);
FORCEPROP 1 LASTPIN (-5650 -1025) $PN 2
J 0
(-5688 -1013);
DISPLAY 0.787234 (-5688 -1013);
PAINT MONO (-5688 -1013);
FORCEPROP 2 LAST CDS_LIB pure_quanta
J 0
(-5750 -1025);
DISPLAY INVISIBLE (-5750 -1025);
FORCEPROP 1 LAST PATH I40
J 0
(-5800 -875);
DISPLAY 0.978723 (-5800 -875);
PAINT WHITE (-5800 -875);
DISPLAY INVISIBLE (-5800 -875);
FORCEPROP 0 LAST CDS_LOCATION R3065
J 0
(-5550 -875);
DISPLAY 1.021277 (-5550 -875);
DISPLAY INVISIBLE (-5550 -875);
FORCEPROP 0 LAST $SEC 1
J 0
(-5550 -875);
DISPLAY 0.680851 (-5550 -875);
PAINT MONO (-5550 -875);
DISPLAY INVISIBLE (-5550 -875);
FORCEPROP 0 LAST CDS_SEC 1
J 0
(-5550 -875);
DISPLAY 1.021277 (-5550 -875);
DISPLAY INVISIBLE (-5550 -875);
FORCEADD OFFPAGE..2
(-3925 -1025);
FORCEPROP 2 LAST $XR0 228 
J 0
(-3736 -1025);
DISPLAY 0.638298 (-3736 -1025);
PAINT MONO (-3736 -1025);
FORCEPROP 2 LAST CDS_LIB standard
J 0
(-3925 -1025);
PAINT MONO (-3925 -1025);
DISPLAY INVISIBLE (-3925 -1025);
FORCEPROP 1 LAST OFFPAGE TRUE
J 0
(-3600 -1150);
DISPLAY 1.170213 (-3600 -1150);
PAINT GREEN (-3600 -1150);
DISPLAY INVISIBLE (-3600 -1150);
FORCEPROP 1 LAST COMMENT_BODY TRUE
J 0
(-3970 -1120);
DISPLAY 1.170213 (-3970 -1120);
PAINT GREEN (-3970 -1120);
DISPLAY INVISIBLE (-3970 -1120);
FORCEPROP 2 LAST PATH I41
J 0
(-3725 -975);
DISPLAY 1.021277 (-3725 -975);
DISPLAY INVISIBLE (-3725 -975);
FORCEADD Q_RES..1
(-5725 -825);
FORCEPROP 1 LAST PART_NUMBER CS03322FB03
J 0
(-5825 -750);
DISPLAY 0.510638 (-5825 -750);
DISPLAY INVISIBLE (-5825 -750);
FORCEPROP 1 LAST MATERIAL CHIP
J 0
(-5425 -825);
DISPLAY 0.510638 (-5425 -825);
FORCEPROP 1 LAST TOLERANCE 1%
J 0
(-5500 -825);
DISPLAY 0.510638 (-5500 -825);
FORCEPROP 1 LAST WATTAGE 1/16W
J 2
(-5525 -700);
DISPLAY 0.510638 (-5525 -700);
FORCEPROP 1 LAST PACK_TYPE 0402LF
J 0
(-5825 -700);
DISPLAY 0.510638 (-5825 -700);
FORCEPROP 1 LAST VALUE 33.2
J 2
(-5525 -825);
DISPLAY 0.510638 (-5525 -825);
FORCEPROP 1 LAST $LOCATION R1300
J 0
(-5975 -825);
DISPLAY 0.638298 (-5975 -825);
FORCEPROP 1 LASTPIN (-5825 -825) $PN 1
J 0
(-5813 -813);
DISPLAY 0.787234 (-5813 -813);
FORCEPROP 1 LASTPIN (-5625 -825) $PN 2
J 0
(-5663 -813);
DISPLAY 0.787234 (-5663 -813);
FORCEPROP 2 LAST CDS_LIB pure_quanta
J 0
(-5725 -825);
PAINT MONO (-5725 -825);
DISPLAY INVISIBLE (-5725 -825);
FORCEPROP 1 LAST PATH I5
J 0
(-5775 -675);
DISPLAY 0.978723 (-5775 -675);
PAINT WHITE (-5775 -675);
DISPLAY INVISIBLE (-5775 -675);
FORCEPROP 1 LAST $LOCATION R1300
J 0
(-5775 -625);
DISPLAY 1.021277 (-5775 -625);
DISPLAY INVISIBLE (-5775 -625);
FORCEPROP 2 LAST CDS_LOCATION R1300
J 0
(-5775 -625);
DISPLAY 1.021277 (-5775 -625);
DISPLAY INVISIBLE (-5775 -625);
FORCEPROP 2 LAST $SEC 1
J 0
(-5775 -625);
DISPLAY 0.680851 (-5775 -625);
PAINT MONO (-5775 -625);
DISPLAY INVISIBLE (-5775 -625);
FORCEPROP 2 LAST CDS_SEC 1
J 0
(-5775 -625);
DISPLAY 1.021277 (-5775 -625);
DISPLAY INVISIBLE (-5775 -625);
FORCEADD OFFPAGE..1
(-7275 -825);
FORCEPROP 2 LAST $XR1 204 
J 0
(-7677 -825);
DISPLAY 0.638298 (-7677 -825);
PAINT MONO (-7677 -825);
FORCEPROP 2 LAST $XR0 183 
J 0
(-7557 -825);
DISPLAY 0.638298 (-7557 -825);
PAINT MONO (-7557 -825);
FORCEPROP 2 LAST CDS_LIB standard
J 0
(-7275 -825);
PAINT MONO (-7275 -825);
DISPLAY INVISIBLE (-7275 -825);
FORCEPROP 1 LAST OFFPAGE TRUE
J 0
(-6950 -950);
DISPLAY 0.872340 (-6950 -950);
PAINT GREEN (-6950 -950);
DISPLAY INVISIBLE (-6950 -950);
FORCEPROP 1 LAST COMMENT_BODY TRUE
J 0
(-7150 -925);
DISPLAY 0.872340 (-7150 -925);
PAINT GREEN (-7150 -925);
DISPLAY INVISIBLE (-7150 -925);
FORCEPROP 2 LAST PATH I6
J 0
(-7225 -750);
DISPLAY 1.021277 (-7225 -750);
DISPLAY INVISIBLE (-7225 -750);
FORCEADD QUANTA_TITLE_BLOCK_C..1
(1000 -4675);
FORCEPROP 0 LAST CDS_CON_LAST_MODIFIED Fri Aug 25 14:03:21 2023
J 0
(-885 -4660);
PAINT MONO (-885 -4660);
DISPLAY INVISIBLE (-885 -4660);
FORCEPROP 1 LAST CUSTOM_TXT_CDS <CON_LAST_MODIFIED>
J 0
(-885 -4660);
DISPLAY 0.978723 (-885 -4660);
FORCEPROP 2 LAST CUSTOM_TXT_CDS <XR_PAGE_TITLE>
J 0
(-6890 575);
DISPLAY 0.638298 (-6890 575);
PAINT PINK (-6890 575);
DISPLAY INVISIBLE (-6890 575);
FORCEPROP 1 LAST CUSTOM_TXT_CDS <NAME_2>
J 0
(-2175 -4625);
FORCEPROP 1 LAST CUSTOM_TXT_CDS <NAME_1>
J 0
(-2175 -4500);
FORCEPROP 1 LAST CUSTOM_TXT_CDS <Q_NUMBER>
J 0
(-403 -4572);
DISPLAY 1.212766 (-403 -4572);
FORCEPROP 1 LAST CUSTOM_TXT_CDS <Q_PROJ>
J 0
(-1382 -4573);
DISPLAY 1.212766 (-1382 -4573);
FORCEPROP 1 LAST CUSTOM_TXT_CDS <Q_REV>
J 0
(816 -4572);
DISPLAY 1.212766 (816 -4572);
FORCEPROP 1 LAST CUSTOM_TXT_CDS <CON_PAGE_NUM> OF <CON_TOTAL_PAGES>
J 0
(554 -4657);
DISPLAY 0.978723 (554 -4657);
FORCEPROP 1 LAST Q_TITLE PCH TERMINATION(2/2)
J 0
(-8266 -4649);
DISPLAY 2.446809 (-8266 -4649);
PAINT GREEN (-8266 -4649);
FORCEPROP 1 LAST Q_DEPT 
J 1
(-2763 -4626);
DISPLAY 1.957447 (-2763 -4626);
PAINT GREEN (-2763 -4626);
FORCEPROP 2 LAST CDS_XR_PAGE_TITLE CR-205 : @S9S_MB_2U_LIB.S9S_MB_2U(SCH_1):PAGE205
J 0
(-6890 575);
DISPLAY 0.638298 (-6890 575);
PAINT PINK (-6890 575);
DISPLAY INVISIBLE (-6890 575);
FORCEPROP 2 LAST CDS_LIB pure_quanta
J 0
(1000 -4675);
PAINT MONO (1000 -4675);
DISPLAY INVISIBLE (1000 -4675);
FORCEPROP 1 LAST CDS_LMAN_SYM_OUTLINE -9475,6775,100,-125
J 0
(1000 -4675);
DISPLAY 0.468085 (1000 -4675);
PAINT GREEN (1000 -4675);
DISPLAY INVISIBLE (1000 -4675);
FORCEPROP 1 LAST COMMENT_BODY TRUE
J 0
(1012 -4688);
DISPLAY 0.978723 (1012 -4688);
PAINT GREEN (1012 -4688);
DISPLAY INVISIBLE (1012 -4688);
FORCEPROP 2 LAST PAGE_BORDER TRUE
J 0
(-6890 575);
DISPLAY 0.638298 (-6890 575);
PAINT PINK (-6890 575);
DISPLAY INVISIBLE (-6890 575);
WIRE 16 -1 (-5825 -2275)(-7225 -2275);
FORCEPROP 0 LAST CDS_PHYS_NET_NAME FM_ADR_TRIGGER_R_N
J 0
(-7060 -2233);
PAINT MONO (-7060 -2233);
DISPLAY INVISIBLE (-7060 -2233);
FORCEPROP 2 LAST SIG_NAME FM_ADR_TRIGGER_R_N
J 0
(-7110 -2265);
DISPLAY 0.851064 (-7110 -2265);
PAINT WHITE (-7110 -2265);
WIRE 16 -1 (-3975 -1800)(-5625 -1800);
FORCEPROP 2 LAST SIG_NAME FM_CPU_RMCA_CATERR_DLY_N
J 0
(-5135 -1790);
DISPLAY 0.851064 (-5135 -1790);
PAINT WHITE (-5135 -1790);
WIRE 16 -1 (-5625 -2275)(-3975 -2275);
FORCEPROP 0 LAST CDS_PHYS_NET_NAME FM_ADR_TRIGGER_N
J 0
(-5085 -2233);
PAINT MONO (-5085 -2233);
DISPLAY INVISIBLE (-5085 -2233);
FORCEPROP 2 LAST SIG_NAME FM_ADR_TRIGGER_N
J 0
(-5135 -2265);
DISPLAY 0.851064 (-5135 -2265);
PAINT WHITE (-5135 -2265);
WIRE 16 -1 (-7225 -1575)(-5825 -1575);
FORCEPROP 2 LAST SIG_NAME FM_ADR_MODE0_R
J 0
(-7110 -1565);
DISPLAY 0.851064 (-7110 -1565);
PAINT WHITE (-7110 -1565);
WIRE 16 -1 (-5625 -1575)(-3975 -1575);
FORCEPROP 2 LAST SIG_NAME FM_ADR_MODE0
J 0
(-5135 -1565);
DISPLAY 0.851064 (-5135 -1565);
PAINT WHITE (-5135 -1565);
WIRE 16 -1 (-7225 -1800)(-5825 -1800);
FORCEPROP 2 LAST SIG_NAME FM_CPU_RMCA_CATERR_DLY_LVT3_R_N
J 0
(-7110 -1790);
DISPLAY 0.680851 (-7110 -1790);
PAINT WHITE (-7110 -1790);
WIRE 16 -1 (-5650 -1025)(-3975 -1025);
FORCEPROP 2 LAST SIG_NAME FM_BIOS_POST_CMPLT_HDR_N
J 0
(-5135 -1015);
DISPLAY 0.851064 (-5135 -1015);
PAINT WHITE (-5135 -1015);
WIRE 16 -1 (-5625 -825)(-3975 -825);
FORCEPROP 2 LAST SIG_NAME FM_BIOS_POST_CMPLT_BMC_N
J 0
(-5135 -815);
DISPLAY 0.851064 (-5135 -815);
PAINT WHITE (-5135 -815);
WIRE 16 -1 (-5600 -525)(-3975 -525);
FORCEPROP 2 LAST SIG_NAME FM_PCH_PLD_GLB_RST_WARN_N
J 0
(-5110 -515);
DISPLAY 0.851064 (-5110 -515);
PAINT WHITE (-5110 -515);
WIRE 16 -1 (-5600 -225)(-3975 -225);
FORCEPROP 2 LAST SIG_NAME IRQ_PCH_CPU_NMI_EVENT_N
J 0
(-5110 -215);
DISPLAY 0.851064 (-5110 -215);
PAINT WHITE (-5110 -215);
WIRE 16 -1 (-6100 -1025)(-5850 -1025);
WIRE 16 -1 (-6100 -825)(-7225 -825);
FORCEPROP 2 LAST SIG_NAME FM_BIOS_POST_CMPLT_N
J 0
(-7110 -815);
DISPLAY 0.851064 (-7110 -815);
PAINT WHITE (-7110 -815);
WIRE 16 -1 (-6100 -825)(-6100 -1025);
WIRE 16 -1 (-5825 -825)(-6100 -825);
WIRE 16 -1 (-7225 -525)(-5800 -525);
FORCEPROP 2 LAST SIG_NAME FM_PCH_GLB_RST_WARN_N
J 0
(-7110 -515);
DISPLAY 0.851064 (-7110 -515);
PAINT WHITE (-7110 -515);
WIRE 16 -1 (-7225 -225)(-5800 -225);
FORCEPROP 2 LAST SIG_NAME IRQ_PCH_CPU_NMI_EVENT_R_N
J 0
(-7110 -215);
DISPLAY 0.851064 (-7110 -215);
PAINT WHITE (-7110 -215);
WIRE 16 -1 (-7225 625)(-5800 625);
FORCEPROP 2 LAST SIG_NAME FM_PS_PWROK_DLY_R_SEL
J 0
(-7110 635);
DISPLAY 0.851064 (-7110 635);
PAINT WHITE (-7110 635);
WIRE 16 -1 (-5600 625)(-3975 625);
FORCEPROP 2 LAST SIG_NAME FM_PS_PWROK_DLY_SEL
J 0
(-5110 635);
DISPLAY 0.851064 (-5110 635);
PAINT WHITE (-5110 635);
WIRE 16 -1 (-7225 75)(-5800 75);
FORCEPROP 2 LAST SIG_NAME IRQ_SMI_ACTIVE_N
J 0
(-7110 85);
DISPLAY 0.851064 (-7110 85);
PAINT WHITE (-7110 85);
WIRE 16 -1 (-5600 75)(-3975 75);
FORCEPROP 2 LAST SIG_NAME IRQ_SMI_ACTIVE_BMC_N
J 0
(-5110 85);
DISPLAY 0.851064 (-5110 85);
PAINT WHITE (-5110 85);
WIRE 16 -1 (-7225 350)(-5800 350);
FORCEPROP 2 LAST SIG_NAME FM_THROTTLE_N
J 0
(-7110 360);
DISPLAY 0.851064 (-7110 360);
PAINT WHITE (-7110 360);
WIRE 16 -1 (-5600 350)(-3975 350);
FORCEPROP 2 LAST SIG_NAME FM_THROTTLE_R_N
J 0
(-5110 360);
DISPLAY 0.851064 (-5110 360);
PAINT WHITE (-5110 360);
DOT 1 (-6100 -825);
QUIT
